# T6G (Grand Teton) — schematic netlist excerpt (pin names and nets, part order shuffled) for the footprints in the layout excerpt that follows; sources: Cadence DE-HDL packaged netlist, KiCad conversion of 04192023_DAF0TMB3IC0_F0TG_MB_C_brd_V02_OCP.brd

R6169  Q_RES  1K 1% EMPTY  pkg 0402LF  page 112 : A = P3V3_AUX ; B = FM_P2E_BUF2_VODA_DB
C101  Q_CAP  1000PF 50V 5% EMPTY  pkg 0402  page 362 : A = PWRGD_P0V9_RETIMER_CPU0_R ; B = GND

(kicad_pcb
	(version 20260206)
	(generator "pcbnew")
	(generator_version "10.0")
	(general
		(thickness 1.6)
		(legacy_teardrops no)
	)
	(paper "A4")
	(title_block
		(title "04192023_DAF0TMB3IC0_F0TG_MB_C_brd_V02_OCP.brd")
		(comment 1 "Grand Teton / footprints 3519-3520 of 8354")
	)
	(layers
		(0 "F.Cu" signal "TOP")
		(4 "In1.Cu" signal "GND")
		(6 "In2.Cu" signal "IN1")
		(8 "In3.Cu" signal "GND1")
		(10 "In4.Cu" signal "IN2")
		(12 "In5.Cu" signal "GND2")
		(14 "In6.Cu" signal "IN3")
		(16 "In7.Cu" signal "GND3")
		(18 "In8.Cu" signal "VCC")
		(20 "In9.Cu" signal "VCC1")
		(22 "In10.Cu" signal "GND4")
		(24 "In11.Cu" signal "IN4")
		(26 "In12.Cu" signal "GND5")
		(28 "In13.Cu" signal "IN5")
		(30 "In14.Cu" signal "GND6")
		(32 "In15.Cu" signal "IN6")
		(34 "In16.Cu" signal "GND7")
		(2 "B.Cu" signal "BOTTOM")
		(9 "F.Adhes" user "F.Adhesive")
		(11 "B.Adhes" user "B.Adhesive")
		(13 "F.Paste" user "Package Geometry/Pastemask Top")
		(15 "B.Paste" user "Package Geometry/Pastemask Bottom")
		(5 "F.SilkS" user "Ref Des/Silkscreen Top")
		(7 "B.SilkS" user "Ref Des/Silkscreen Bottom")
		(1 "F.Mask" user "Board Geometry/Soldermask Top")
		(3 "B.Mask" user "Board Geometry/Soldermask Bottom")
		(17 "Dwgs.User" user "User.Drawings")
		(19 "Cmts.User" user "User.Comments")
		(21 "Eco1.User" user "User.Eco1")
		(23 "Eco2.User" user "User.Eco2")
		(25 "Edge.Cuts" user "Board Geometry/Outline")
		(27 "Margin" user)
		(31 "F.CrtYd" user "Package Geometry/Place Bound Top")
		(29 "B.CrtYd" user "Package Geometry/Place Bound Bottom")
		(35 "F.Fab" user "Ref Des/Assembly Top")
		(33 "B.Fab" user "Ref Des/Assembly Bottom")
	)
	(footprint ""
		(layer "F.Cu")
		(at 439.029602 -427.09211 180)
		(property "Reference" "C101"
			(at 0 0 180)
			(layer "F.SilkS")
			(hide yes)
			(effects
				(font
					(size 1.27 1.27)
				)
			)
		)
		(property "Value" ""
			(at 0 0 180)
			(layer "F.Fab")
			(effects
				(font
					(size 1.27 1.27)
				)
			)
		)
		(duplicate_pad_numbers_are_jumpers no)
		(fp_line
			(start 0.7874 0.4064)
			(end -0.7874 0.4064)
			(stroke
				(width 0.1524)
				(type default)
			)
			(layer "F.SilkS")
		)
		(fp_line
			(start 0.7874 -0.4064)
			(end 0.7874 0.4064)
			(stroke
				(width 0.1524)
				(type default)
			)
			(layer "F.SilkS")
		)
		(fp_line
			(start -0.7874 0.4064)
			(end -0.7874 -0.4064)
			(stroke
				(width 0.1524)
				(type default)
			)
			(layer "F.SilkS")
		)
		(fp_line
			(start -0.7874 -0.4064)
			(end 0.7874 -0.4064)
			(stroke
				(width 0.1524)
				(type default)
			)
			(layer "F.SilkS")
		)
		(fp_line
			(start 0.67945 0.3048)
			(end 0.120396 0.3048)
			(stroke
				(width 0.1)
				(type default)
			)
			(layer "F.Fab")
		)
		(fp_line
			(start 0.67945 -0.3048)
			(end 0.67945 0.3048)
			(stroke
				(width 0.1)
				(type default)
			)
			(layer "F.Fab")
		)
		(fp_line
			(start 0.12065 -0.2794)
			(end 0.12065 -0.3048)
			(stroke
				(width 0.1)
				(type default)
			)
			(layer "F.Fab")
		)
		(fp_line
			(start 0.12065 -0.3048)
			(end 0.67945 -0.3048)
			(stroke
				(width 0.1)
				(type default)
			)
			(layer "F.Fab")
		)
		(fp_line
			(start 0.120396 0.3048)
			(end 0.120396 0.2794)
			(stroke
				(width 0.1)
				(type default)
			)
			(layer "F.Fab")
		)
		(fp_line
			(start 0.120396 0.2794)
			(end -0.12065 0.2794)
			(stroke
				(width 0.1)
				(type default)
			)
			(layer "F.Fab")
		)
		(fp_line
			(start -0.12065 0.3048)
			(end -0.67945 0.3048)
			(stroke
				(width 0.1)
				(type default)
			)
			(layer "F.Fab")
		)
		(fp_line
			(start -0.12065 0.2794)
			(end -0.12065 0.3048)
			(stroke
				(width 0.1)
				(type default)
			)
			(layer "F.Fab")
		)
		(fp_line
			(start -0.12065 -0.2794)
			(end 0.12065 -0.2794)
			(stroke
				(width 0.1)
				(type default)
			)
			(layer "F.Fab")
		)
		(fp_line
			(start -0.12065 -0.305054)
			(end -0.12065 -0.2794)
			(stroke
				(width 0.1)
				(type default)
			)
			(layer "F.Fab")
		)
		(fp_line
			(start -0.67945 0.3048)
			(end -0.67945 -0.305054)
			(stroke
				(width 0.1)
				(type default)
			)
			(layer "F.Fab")
		)
		(fp_line
			(start -0.67945 -0.305054)
			(end -0.12065 -0.305054)
			(stroke
				(width 0.1)
				(type default)
			)
			(layer "F.Fab")
		)
		(pad "1" smd circle
			(at -0.40005 0 180)
			(size 0 0)
			(layers "F.Cu" "F.Mask" "F.Paste")
			(net "PWRGD_P0V9_RETIMER_CPU0_R")
		)
		(pad "2" smd circle
			(at 0.40005 0 180)
			(size 0 0)
			(layers "F.Cu" "F.Mask" "F.Paste")
			(net "GND")
		)
	)
	(footprint ""
		(layer "F.Cu")
		(at 16.796258 -427.580298 -90)
		(property "Reference" "R6169"
			(at 0 0 270)
			(layer "F.SilkS")
			(hide yes)
			(effects
				(font
					(size 1.27 1.27)
				)
			)
		)
		(property "Value" ""
			(at 0 0 270)
			(layer "F.Fab")
			(effects
				(font
					(size 1.27 1.27)
				)
			)
		)
		(duplicate_pad_numbers_are_jumpers no)
		(fp_line
			(start -0.7874 0.4064)
			(end -0.7874 -0.4064)
			(stroke
				(width 0.1524)
				(type default)
			)
			(layer "F.SilkS")
		)
		(fp_line
			(start 0.7874 0.4064)
			(end -0.7874 0.4064)
			(stroke
				(width 0.1524)
				(type default)
			)
			(layer "F.SilkS")
		)
		(fp_line
			(start -0.7874 -0.4064)
			(end 0.7874 -0.4064)
			(stroke
				(width 0.1524)
				(type default)
			)
			(layer "F.SilkS")
		)
		(fp_line
			(start 0.7874 -0.4064)
			(end 0.7874 0.4064)
			(stroke
				(width 0.1524)
				(type default)
			)
			(layer "F.SilkS")
		)
		(fp_line
			(start -0.67945 0.3048)
			(end -0.67945 -0.305054)
			(stroke
				(width 0.1)
				(type default)
			)
			(layer "F.Fab")
		)
		(fp_line
			(start -0.12065 0.3048)
			(end -0.67945 0.3048)
			(stroke
				(width 0.1)
				(type default)
			)
			(layer "F.Fab")
		)
		(fp_line
			(start 0.120396 0.3048)
			(end 0.120396 0.2794)
			(stroke
				(width 0.1)
				(type default)
			)
			(layer "F.Fab")
		)
		(fp_line
			(start 0.67945 0.3048)
			(end 0.120396 0.3048)
			(stroke
				(width 0.1)
				(type default)
			)
			(layer "F.Fab")
		)
		(fp_line
			(start -0.12065 0.2794)
			(end -0.12065 0.3048)
			(stroke
				(width 0.1)
				(type default)
			)
			(layer "F.Fab")
		)
		(fp_line
			(start 0.120396 0.2794)
			(end -0.12065 0.2794)
			(stroke
				(width 0.1)
				(type default)
			)
			(layer "F.Fab")
		)
		(fp_line
			(start -0.12065 -0.2794)
			(end 0.12065 -0.2794)
			(stroke
				(width 0.1)
				(type default)
			)
			(layer "F.Fab")
		)
		(fp_line
			(start 0.12065 -0.2794)
			(end 0.12065 -0.3048)
			(stroke
				(width 0.1)
				(type default)
			)
			(layer "F.Fab")
		)
		(fp_line
			(start 0.12065 -0.3048)
			(end 0.67945 -0.3048)
			(stroke
				(width 0.1)
				(type default)
			)
			(layer "F.Fab")
		)
		(fp_line
			(start 0.67945 -0.3048)
			(end 0.67945 0.3048)
			(stroke
				(width 0.1)
				(type default)
			)
			(layer "F.Fab")
		)
		(fp_line
			(start -0.67945 -0.305054)
			(end -0.12065 -0.305054)
			(stroke
				(width 0.1)
				(type default)
			)
			(layer "F.Fab")
		)
		(fp_line
			(start -0.12065 -0.305054)
			(end -0.12065 -0.2794)
			(stroke
				(width 0.1)
				(type default)
			)
			(layer "F.Fab")
		)
		(pad "1" smd circle
			(at -0.40005 0 270)
			(size 0 0)
			(layers "F.Cu" "F.Mask" "F.Paste")
			(net "P3V3_AUX")
		)
		(pad "2" smd circle
			(at 0.40005 0 270)
			(size 0 0)
			(layers "F.Cu" "F.Mask" "F.Paste")
			(net "FM_P2E_BUF2_VODA_DB")
		)
	)
)
